# T6G (Grand Teton) — schematic netlist excerpt (pin names and nets, part order shuffled) for the footprints in the layout excerpt that follows; sources: Cadence DE-HDL packaged netlist, KiCad conversion of 04192023_DAF0TMB3IC0_F0TG_MB_C_brd_V02_OCP.brd

C6096  Q_CAP  1PF 50V 0.05P COG  pkg C0402  page 179 : A = P3V3_AUX_CPU0_USB2_AVDD33 ; B = GND
C2326  Q_CAP  22UF 4V 20% X6S  pkg C0402  page 73 : A = PVDDCR_CPU0_P1 ; B = GND

(kicad_pcb
	(version 20260206)
	(generator "pcbnew")
	(generator_version "10.0")
	(general
		(thickness 1.6)
		(legacy_teardrops no)
	)
	(paper "A4")
	(title_block
		(title "04192023_DAF0TMB3IC0_F0TG_MB_C_brd_V02_OCP.brd")
		(comment 1 "Grand Teton / footprints 7821-7822 of 8354")
	)
	(layers
		(0 "F.Cu" signal "TOP")
		(4 "In1.Cu" signal "GND")
		(6 "In2.Cu" signal "IN1")
		(8 "In3.Cu" signal "GND1")
		(10 "In4.Cu" signal "IN2")
		(12 "In5.Cu" signal "GND2")
		(14 "In6.Cu" signal "IN3")
		(16 "In7.Cu" signal "GND3")
		(18 "In8.Cu" signal "VCC")
		(20 "In9.Cu" signal "VCC1")
		(22 "In10.Cu" signal "GND4")
		(24 "In11.Cu" signal "IN4")
		(26 "In12.Cu" signal "GND5")
		(28 "In13.Cu" signal "IN5")
		(30 "In14.Cu" signal "GND6")
		(32 "In15.Cu" signal "IN6")
		(34 "In16.Cu" signal "GND7")
		(2 "B.Cu" signal "BOTTOM")
		(9 "F.Adhes" user "F.Adhesive")
		(11 "B.Adhes" user "B.Adhesive")
		(13 "F.Paste" user "Package Geometry/Pastemask Top")
		(15 "B.Paste" user "Package Geometry/Pastemask Bottom")
		(5 "F.SilkS" user "Ref Des/Silkscreen Top")
		(7 "B.SilkS" user "Ref Des/Silkscreen Bottom")
		(1 "F.Mask" user "Board Geometry/Soldermask Top")
		(3 "B.Mask" user "Board Geometry/Soldermask Bottom")
		(17 "Dwgs.User" user "User.Drawings")
		(19 "Cmts.User" user "User.Comments")
		(21 "Eco1.User" user "User.Eco1")
		(23 "Eco2.User" user "User.Eco2")
		(25 "Edge.Cuts" user "Board Geometry/Outline")
		(27 "Margin" user)
		(31 "F.CrtYd" user "Package Geometry/Place Bound Top")
		(29 "B.CrtYd" user "Package Geometry/Place Bound Bottom")
		(35 "F.Fab" user "Ref Des/Assembly Top")
		(33 "B.Fab" user "Ref Des/Assembly Bottom")
	)
	(footprint ""
		(layer "B.Cu")
		(at 109.150404 -28.70327 -90)
		(property "Reference" "C6096"
			(at 0 0 90)
			(layer "B.SilkS")
			(hide yes)
			(effects
				(font
					(size 1.27 1.27)
				)
				(justify mirror)
			)
		)
		(property "Value" ""
			(at 0 0 90)
			(layer "B.Fab")
			(effects
				(font
					(size 1.27 1.27)
				)
				(justify mirror)
			)
		)
		(duplicate_pad_numbers_are_jumpers no)
		(fp_line
			(start -0.7874 0.4064)
			(end 0.7874 0.4064)
			(stroke
				(width 0.1524)
				(type default)
			)
			(layer "B.SilkS")
		)
		(fp_line
			(start 0.7874 0.4064)
			(end 0.7874 -0.4064)
			(stroke
				(width 0.1524)
				(type default)
			)
			(layer "B.SilkS")
		)
		(fp_line
			(start -0.7874 -0.4064)
			(end -0.7874 0.4064)
			(stroke
				(width 0.1524)
				(type default)
			)
			(layer "B.SilkS")
		)
		(fp_line
			(start 0.7874 -0.4064)
			(end -0.7874 -0.4064)
			(stroke
				(width 0.1524)
				(type default)
			)
			(layer "B.SilkS")
		)
		(fp_line
			(start -0.67945 0.3048)
			(end -0.120396 0.3048)
			(stroke
				(width 0.1)
				(type default)
			)
			(layer "B.Fab")
		)
		(fp_line
			(start -0.120396 0.3048)
			(end -0.120396 0.2794)
			(stroke
				(width 0.1)
				(type default)
			)
			(layer "B.Fab")
		)
		(fp_line
			(start 0.12065 0.3048)
			(end 0.67945 0.3048)
			(stroke
				(width 0.1)
				(type default)
			)
			(layer "B.Fab")
		)
		(fp_line
			(start 0.67945 0.3048)
			(end 0.67945 -0.305054)
			(stroke
				(width 0.1)
				(type default)
			)
			(layer "B.Fab")
		)
		(fp_line
			(start -0.120396 0.2794)
			(end 0.12065 0.2794)
			(stroke
				(width 0.1)
				(type default)
			)
			(layer "B.Fab")
		)
		(fp_line
			(start 0.12065 0.2794)
			(end 0.12065 0.3048)
			(stroke
				(width 0.1)
				(type default)
			)
			(layer "B.Fab")
		)
		(fp_line
			(start -0.12065 -0.2794)
			(end -0.12065 -0.3048)
			(stroke
				(width 0.1)
				(type default)
			)
			(layer "B.Fab")
		)
		(fp_line
			(start 0.12065 -0.2794)
			(end -0.12065 -0.2794)
			(stroke
				(width 0.1)
				(type default)
			)
			(layer "B.Fab")
		)
		(fp_line
			(start -0.67945 -0.3048)
			(end -0.67945 0.3048)
			(stroke
				(width 0.1)
				(type default)
			)
			(layer "B.Fab")
		)
		(fp_line
			(start -0.12065 -0.3048)
			(end -0.67945 -0.3048)
			(stroke
				(width 0.1)
				(type default)
			)
			(layer "B.Fab")
		)
		(fp_line
			(start 0.12065 -0.305054)
			(end 0.12065 -0.2794)
			(stroke
				(width 0.1)
				(type default)
			)
			(layer "B.Fab")
		)
		(fp_line
			(start 0.67945 -0.305054)
			(end 0.12065 -0.305054)
			(stroke
				(width 0.1)
				(type default)
			)
			(layer "B.Fab")
		)
		(pad "1" smd circle
			(at 0.40005 0 90)
			(size 0 0)
			(layers "B.Cu" "B.Mask" "B.Paste")
			(net "P3V3_AUX_CPU0_USB2_AVDD33")
		)
		(pad "2" smd circle
			(at -0.40005 0 90)
			(size 0 0)
			(layers "B.Cu" "B.Mask" "B.Paste")
			(net "GND")
		)
	)
	(footprint ""
		(layer "B.Cu")
		(at 101.38029 -248.479564 180)
		(property "Reference" "C2326"
			(at 0 0 0)
			(layer "B.SilkS")
			(hide yes)
			(effects
				(font
					(size 1.27 1.27)
				)
				(justify mirror)
			)
		)
		(property "Value" ""
			(at 0 0 0)
			(layer "B.Fab")
			(effects
				(font
					(size 1.27 1.27)
				)
				(justify mirror)
			)
		)
		(duplicate_pad_numbers_are_jumpers no)
		(fp_line
			(start 0.7874 0.4064)
			(end 0.7874 -0.4064)
			(stroke
				(width 0.1524)
				(type default)
			)
			(layer "B.SilkS")
		)
		(fp_line
			(start 0.7874 -0.4064)
			(end -0.7874 -0.4064)
			(stroke
				(width 0.1524)
				(type default)
			)
			(layer "B.SilkS")
		)
		(fp_line
			(start -0.7874 0.4064)
			(end 0.7874 0.4064)
			(stroke
				(width 0.1524)
				(type default)
			)
			(layer "B.SilkS")
		)
		(fp_line
			(start -0.7874 -0.4064)
			(end -0.7874 0.4064)
			(stroke
				(width 0.1524)
				(type default)
			)
			(layer "B.SilkS")
		)
		(fp_line
			(start 0.67945 0.3048)
			(end 0.67945 -0.305054)
			(stroke
				(width 0.1)
				(type default)
			)
			(layer "B.Fab")
		)
		(fp_line
			(start 0.67945 -0.305054)
			(end 0.12065 -0.305054)
			(stroke
				(width 0.1)
				(type default)
			)
			(layer "B.Fab")
		)
		(fp_line
			(start 0.12065 0.3048)
			(end 0.67945 0.3048)
			(stroke
				(width 0.1)
				(type default)
			)
			(layer "B.Fab")
		)
		(fp_line
			(start 0.12065 0.2794)
			(end 0.12065 0.3048)
			(stroke
				(width 0.1)
				(type default)
			)
			(layer "B.Fab")
		)
		(fp_line
			(start 0.12065 -0.2794)
			(end -0.12065 -0.2794)
			(stroke
				(width 0.1)
				(type default)
			)
			(layer "B.Fab")
		)
		(fp_line
			(start 0.12065 -0.305054)
			(end 0.12065 -0.2794)
			(stroke
				(width 0.1)
				(type default)
			)
			(layer "B.Fab")
		)
		(fp_line
			(start -0.120396 0.3048)
			(end -0.120396 0.2794)
			(stroke
				(width 0.1)
				(type default)
			)
			(layer "B.Fab")
		)
		(fp_line
			(start -0.120396 0.2794)
			(end 0.12065 0.2794)
			(stroke
				(width 0.1)
				(type default)
			)
			(layer "B.Fab")
		)
		(fp_line
			(start -0.12065 -0.2794)
			(end -0.12065 -0.3048)
			(stroke
				(width 0.1)
				(type default)
			)
			(layer "B.Fab")
		)
		(fp_line
			(start -0.12065 -0.3048)
			(end -0.67945 -0.3048)
			(stroke
				(width 0.1)
				(type default)
			)
			(layer "B.Fab")
		)
		(fp_line
			(start -0.67945 0.3048)
			(end -0.120396 0.3048)
			(stroke
				(width 0.1)
				(type default)
			)
			(layer "B.Fab")
		)
		(fp_line
			(start -0.67945 -0.3048)
			(end -0.67945 0.3048)
			(stroke
				(width 0.1)
				(type default)
			)
			(layer "B.Fab")
		)
		(pad "1" smd circle
			(at 0.40005 0)
			(size 0 0)
			(layers "B.Cu" "B.Mask" "B.Paste")
			(net "PVDDCR_CPU0_P1")
		)
		(pad "2" smd circle
			(at -0.40005 0)
			(size 0 0)
			(layers "B.Cu" "B.Mask" "B.Paste")
			(net "GND")
		)
	)
)
